(kicad_pcb
	(version 20260206)
	(generator "pcbnew")
	(generator_version "10.0")
	(general
		(thickness 1.6)
		(legacy_teardrops no)
	)
	(paper "A4")
	(title_block
		(title "dpb — 14545-sa.0730WZS0815.brd")
		(comment 1 "Honey Badger (Wiwynn) / footprints 765-771 of 1066")
	)
	(layers
		(0 "F.Cu" signal "TOP")
		(4 "In1.Cu" signal "L2GND")
		(6 "In2.Cu" signal "L3")
		(8 "In3.Cu" signal "L4VCC")
		(10 "In4.Cu" signal "L5VCC")
		(12 "In5.Cu" signal "L6")
		(14 "In6.Cu" signal "L7GND")
		(2 "B.Cu" signal "BOTTOM")
		(9 "F.Adhes" user "F.Adhesive")
		(11 "B.Adhes" user "B.Adhesive")
		(13 "F.Paste" user "Package Geometry/Pastemask Top")
		(15 "B.Paste" user "Package Geometry/Pastemask Bottom")
		(5 "F.SilkS" user "Ref Des/Silkscreen Top")
		(7 "B.SilkS" user "Ref Des/Silkscreen Bottom")
		(1 "F.Mask" user "Board Geometry/Soldermask Top")
		(3 "B.Mask" user "Board Geometry/Soldermask Bottom")
		(17 "Dwgs.User" user "User.Drawings")
		(19 "Cmts.User" user "User.Comments")
		(21 "Eco1.User" user "User.Eco1")
		(23 "Eco2.User" user "User.Eco2")
		(25 "Edge.Cuts" user "Board Geometry/Outline")
		(27 "Margin" user)
		(31 "F.CrtYd" user "Package Geometry/Place Bound Top")
		(29 "B.CrtYd" user "Package Geometry/Place Bound Bottom")
		(35 "F.Fab" user "Ref Des/Assembly Top")
		(33 "B.Fab" user "Ref Des/Assembly Bottom")
	)
	(footprint ""
		(layer "F.Cu")
		(at 56.752744 -481.42271 180)
		(property "Reference" "R176"
			(at 0 0 180)
			(layer "F.SilkS")
			(hide yes)
			(effects
				(font
					(size 1.27 1.27)
				)
			)
		)
		(property "Value" "4K7R2J-2-GP"
			(at 0.064008 -3.993896 180)
			(unlocked yes)
			(layer "F.Fab")
			(hide yes)
			(effects
				(font
					(size 1.016 1.016)
					(thickness 0.1524)
				)
			)
		)
		(property "Device Type" "R402H16"
			(at 0.064008 -5.517896 180)
			(unlocked yes)
			(layer "F.Fab")
			(hide yes)
			(effects
				(font
					(size 1.016 1.016)
					(thickness 0.1524)
				)
			)
		)
		(duplicate_pad_numbers_are_jumpers no)
		(fp_line
			(start 0.508 -0.9398)
			(end -0.508 -0.9398)
			(stroke
				(width 0.1524)
				(type default)
			)
			(layer "F.SilkS")
		)
		(fp_line
			(start -0.508 -0.9398)
			(end -0.508 0.9398)
			(stroke
				(width 0.1524)
				(type default)
			)
			(layer "F.SilkS")
		)
		(fp_rect
			(start -0.508 0.9398)
			(end 0.508 -0.9398)
			(stroke
				(width 0)
				(type default)
			)
			(fill no)
			(layer "F.CrtYd")
		)
		(fp_rect
			(start -0.508 0.9398)
			(end 0.508 -0.9398)
			(stroke
				(width 0)
				(type default)
			)
			(fill no)
			(layer "F.Fab")
		)
		(pad "1" smd custom
			(at 0 -0.4445 180)
			(size 0.1397 0.1397)
			(layers "F.Cu" "F.Mask" "F.Paste")
			(net "P3V3")
			(options
				(clearance outline)
				(anchor circle)
			)
			(primitives
				(gr_poly
					(pts
						(arc
							(start -0.1778 -0.2794)
							(mid -0.249642 -0.249642)
							(end -0.2794 -0.1778)
						)
						(arc
							(start -0.2794 0.1778)
							(mid -0.249642 0.249642)
							(end -0.1778 0.2794)
						)
						(arc
							(start 0.1778 0.2794)
							(mid 0.249642 0.249642)
							(end 0.2794 0.1778)
						)
						(arc
							(start 0.2794 -0.1778)
							(mid 0.249642 -0.249642)
							(end 0.1778 -0.2794)
						)
					)
					(width 0)
					(fill yes)
				)
			)
		)
		(pad "2" smd custom
			(at 0 0.4445 180)
			(size 0.1397 0.1397)
			(layers "F.Cu" "F.Mask" "F.Paste")
			(net "HDD_PRSNT_NET5")
			(options
				(clearance outline)
				(anchor circle)
			)
			(primitives
				(gr_poly
					(pts
						(arc
							(start -0.1778 -0.2794)
							(mid -0.249642 -0.249642)
							(end -0.2794 -0.1778)
						)
						(arc
							(start -0.2794 0.1778)
							(mid -0.249642 0.249642)
							(end -0.1778 0.2794)
						)
						(arc
							(start 0.1778 0.2794)
							(mid 0.249642 0.249642)
							(end 0.2794 0.1778)
						)
						(arc
							(start 0.2794 -0.1778)
							(mid 0.249642 -0.249642)
							(end 0.1778 -0.2794)
						)
					)
					(width 0)
					(fill yes)
				)
			)
		)
	)
	(footprint ""
		(layer "F.Cu")
		(at 4.445 -278.765 90)
		(property "Reference" "C148"
			(at 0 0 90)
			(layer "F.SilkS")
			(hide yes)
			(effects
				(font
					(size 1.27 1.27)
				)
			)
		)
		(property "Value" "SC1U25V3KX-1-GP"
			(at 0 -2.8194 90)
			(unlocked yes)
			(layer "F.Fab")
			(hide yes)
			(effects
				(font
					(size 1.016 1.016)
					(thickness 0.1524)
				)
			)
		)
		(property "Device Type" "C603H36"
			(at 0 -4.3434 90)
			(unlocked yes)
			(layer "F.Fab")
			(hide yes)
			(effects
				(font
					(size 1.016 1.016)
					(thickness 0.1524)
				)
			)
		)
		(duplicate_pad_numbers_are_jumpers no)
		(fp_line
			(start 0.508 0)
			(end -0.508 0)
			(stroke
				(width 0.2032)
				(type default)
			)
			(layer "F.SilkS")
		)
		(fp_rect
			(start -0.5842 1.3335)
			(end 0.5842 -1.3335)
			(stroke
				(width 0)
				(type default)
			)
			(fill no)
			(layer "F.CrtYd")
		)
		(fp_rect
			(start -0.5842 1.3335)
			(end 0.5842 -1.3335)
			(stroke
				(width 0)
				(type default)
			)
			(fill no)
			(layer "F.Fab")
		)
		(pad "1" smd custom
			(at 0 -0.762 90)
			(size 0.2159 0.2159)
			(layers "F.Cu" "F.Mask" "F.Paste")
			(net "P12V")
			(options
				(clearance outline)
				(anchor circle)
			)
			(primitives
				(gr_poly
					(pts
						(arc
							(start -0.3302 -0.4318)
							(mid -0.402042 -0.402042)
							(end -0.4318 -0.3302)
						)
						(arc
							(start -0.4318 0.3302)
							(mid -0.402042 0.402042)
							(end -0.3302 0.4318)
						)
						(arc
							(start 0.3302 0.4318)
							(mid 0.402042 0.402042)
							(end 0.4318 0.3302)
						)
						(arc
							(start 0.4318 -0.3302)
							(mid 0.402042 -0.402042)
							(end 0.3302 -0.4318)
						)
					)
					(width 0)
					(fill yes)
				)
			)
		)
		(pad "2" smd custom
			(at 0 0.762 90)
			(size 0.2159 0.2159)
			(layers "F.Cu" "F.Mask" "F.Paste")
			(net "GND")
			(options
				(clearance outline)
				(anchor circle)
			)
			(primitives
				(gr_poly
					(pts
						(arc
							(start -0.3302 -0.4318)
							(mid -0.402042 -0.402042)
							(end -0.4318 -0.3302)
						)
						(arc
							(start -0.4318 0.3302)
							(mid -0.402042 0.402042)
							(end -0.3302 0.4318)
						)
						(arc
							(start 0.3302 0.4318)
							(mid 0.402042 0.402042)
							(end 0.4318 0.3302)
						)
						(arc
							(start 0.4318 -0.3302)
							(mid 0.402042 -0.402042)
							(end 0.3302 -0.4318)
						)
					)
					(width 0)
					(fill yes)
				)
			)
		)
	)
	(footprint ""
		(layer "F.Cu")
		(at 225.323654 -438.7723 90)
		(property "Reference" "PR53"
			(at 0 0 90)
			(layer "F.SilkS")
			(hide yes)
			(effects
				(font
					(size 1.27 1.27)
				)
			)
		)
		(property "Value" "470KR2F-GP"
			(at 0.064008 -3.993896 90)
			(unlocked yes)
			(layer "F.Fab")
			(hide yes)
			(effects
				(font
					(size 1.016 1.016)
					(thickness 0.1524)
				)
			)
		)
		(property "Device Type" "R402H16"
			(at 0.064008 -5.517896 90)
			(unlocked yes)
			(layer "F.Fab")
			(hide yes)
			(effects
				(font
					(size 1.016 1.016)
					(thickness 0.1524)
				)
			)
		)
		(duplicate_pad_numbers_are_jumpers no)
		(fp_line
			(start 0.508 -0.9398)
			(end -0.508 -0.9398)
			(stroke
				(width 0.1524)
				(type default)
			)
			(layer "F.SilkS")
		)
		(fp_line
			(start -0.508 -0.9398)
			(end -0.508 0.9398)
			(stroke
				(width 0.1524)
				(type default)
			)
			(layer "F.SilkS")
		)
		(fp_rect
			(start -0.508 0.9398)
			(end 0.508 -0.9398)
			(stroke
				(width 0)
				(type default)
			)
			(fill no)
			(layer "F.CrtYd")
		)
		(fp_rect
			(start -0.508 0.9398)
			(end 0.508 -0.9398)
			(stroke
				(width 0)
				(type default)
			)
			(fill no)
			(layer "F.Fab")
		)
		(pad "1" smd custom
			(at 0 -0.4445 90)
			(size 0.1397 0.1397)
			(layers "F.Cu" "F.Mask" "F.Paste")
			(net "P3V3_EN")
			(options
				(clearance outline)
				(anchor circle)
			)
			(primitives
				(gr_poly
					(pts
						(arc
							(start -0.1778 -0.2794)
							(mid -0.249642 -0.249642)
							(end -0.2794 -0.1778)
						)
						(arc
							(start -0.2794 0.1778)
							(mid -0.249642 0.249642)
							(end -0.1778 0.2794)
						)
						(arc
							(start 0.1778 0.2794)
							(mid 0.249642 0.249642)
							(end 0.2794 0.1778)
						)
						(arc
							(start 0.2794 -0.1778)
							(mid 0.249642 -0.249642)
							(end 0.1778 -0.2794)
						)
					)
					(width 0)
					(fill yes)
				)
			)
		)
		(pad "2" smd custom
			(at 0 0.4445 90)
			(size 0.1397 0.1397)
			(layers "F.Cu" "F.Mask" "F.Paste")
			(net "GND")
			(options
				(clearance outline)
				(anchor circle)
			)
			(primitives
				(gr_poly
					(pts
						(arc
							(start -0.1778 -0.2794)
							(mid -0.249642 -0.249642)
							(end -0.2794 -0.1778)
						)
						(arc
							(start -0.2794 0.1778)
							(mid -0.249642 0.249642)
							(end -0.1778 0.2794)
						)
						(arc
							(start 0.1778 0.2794)
							(mid 0.249642 0.249642)
							(end 0.2794 0.1778)
						)
						(arc
							(start 0.2794 -0.1778)
							(mid 0.249642 -0.249642)
							(end 0.1778 -0.2794)
						)
					)
					(width 0)
					(fill yes)
				)
			)
		)
	)
	(footprint ""
		(layer "F.Cu")
		(at 194.177412 -82.911696 -90)
		(property "Reference" "U15"
			(at 0 0 270)
			(layer "F.SilkS")
			(hide yes)
			(effects
				(font
					(size 1.27 1.27)
				)
			)
		)
		(property "Value" "74LVC1G08GW-1-GP"
			(at -2.3368 -8.6868 270)
			(unlocked yes)
			(layer "F.Fab")
			(hide yes)
			(effects
				(font
					(size 1.016 1.016)
					(thickness 0.1524)
				)
			)
		)
		(property "Device Type" "SC70-5H44"
			(at -2.3114 -10.414 270)
			(unlocked yes)
			(layer "F.Fab")
			(hide yes)
			(effects
				(font
					(size 1.016 1.016)
					(thickness 0.1524)
				)
			)
		)
		(duplicate_pad_numbers_are_jumpers no)
		(fp_line
			(start -1.27 1.7018)
			(end -1.27 -1.7018)
			(stroke
				(width 0.1524)
				(type default)
			)
			(layer "F.SilkS")
		)
		(fp_line
			(start 1.27 1.7018)
			(end -1.27 1.7018)
			(stroke
				(width 0.1524)
				(type default)
			)
			(layer "F.SilkS")
		)
		(fp_line
			(start -1.27 -1.7018)
			(end 1.27 -1.7018)
			(stroke
				(width 0.1524)
				(type default)
			)
			(layer "F.SilkS")
		)
		(fp_line
			(start 1.27 -1.7018)
			(end 1.27 1.7018)
			(stroke
				(width 0.1524)
				(type default)
			)
			(layer "F.SilkS")
		)
		(fp_line
			(start 0.6604 -1.8034)
			(end 1.3843 -1.8034)
			(stroke
				(width 0.3302)
				(type default)
			)
			(layer "F.SilkS")
		)
		(fp_line
			(start 1.3843 -1.8034)
			(end 1.3843 -1.1176)
			(stroke
				(width 0.3302)
				(type default)
			)
			(layer "F.SilkS")
		)
		(fp_rect
			(start -1.524 1.9558)
			(end 1.524 -1.9558)
			(stroke
				(width 0)
				(type default)
			)
			(fill no)
			(layer "F.CrtYd")
		)
		(fp_poly
			(pts
				(xy -1.524 -1.9558) (xy 1.524 -1.9558) (xy 1.524 1.9558) (xy -1.524 1.9558)
			)
			(stroke
				(width 0)
				(type default)
			)
			(fill no)
			(layer "F.Fab")
		)
		(pad "1" smd rect
			(at 0.65024 -0.8255 270)
			(size 0.4064 1.2192)
			(layers "F.Cu" "F.Mask" "F.Paste")
			(net "SAS_EXP_B_PWR4")
		)
		(pad "2" smd rect
			(at 0 -0.8255 270)
			(size 0.4064 1.2192)
			(layers "F.Cu" "F.Mask" "F.Paste")
			(net "SAS_EXP_A_PWR4")
		)
		(pad "3" smd rect
			(at -0.65024 -0.8255 270)
			(size 0.4064 1.2192)
			(layers "F.Cu" "F.Mask" "F.Paste")
			(net "GND")
		)
		(pad "4" smd rect
			(at -0.65024 0.8255 270)
			(size 0.4064 1.2192)
			(layers "F.Cu" "F.Mask" "F.Paste")
			(net "DRIVE_PWR4")
		)
		(pad "5" smd rect
			(at 0.65024 0.8255 270)
			(size 0.4064 1.2192)
			(layers "F.Cu" "F.Mask" "F.Paste")
			(net "P3V3")
		)
	)
	(footprint ""
		(layer "F.Cu")
		(at 229.615746 -27.1907 -90)
		(property "Reference" "PR15"
			(at 0 0 270)
			(layer "F.SilkS")
			(hide yes)
			(effects
				(font
					(size 1.27 1.27)
				)
			)
		)
		(property "Value" "0R2J-2-GP"
			(at 0.064008 -3.993896 270)
			(unlocked yes)
			(layer "F.Fab")
			(hide yes)
			(effects
				(font
					(size 1.016 1.016)
					(thickness 0.1524)
				)
			)
		)
		(property "Device Type" "R402H16"
			(at 0.064008 -5.517896 270)
			(unlocked yes)
			(layer "F.Fab")
			(hide yes)
			(effects
				(font
					(size 1.016 1.016)
					(thickness 0.1524)
				)
			)
		)
		(duplicate_pad_numbers_are_jumpers no)
		(fp_line
			(start -0.508 -0.9398)
			(end -0.508 0.9398)
			(stroke
				(width 0.1524)
				(type default)
			)
			(layer "F.SilkS")
		)
		(fp_line
			(start 0.508 -0.9398)
			(end -0.508 -0.9398)
			(stroke
				(width 0.1524)
				(type default)
			)
			(layer "F.SilkS")
		)
		(fp_rect
			(start -0.508 0.9398)
			(end 0.508 -0.9398)
			(stroke
				(width 0)
				(type default)
			)
			(fill no)
			(layer "F.CrtYd")
		)
		(fp_rect
			(start -0.508 0.9398)
			(end 0.508 -0.9398)
			(stroke
				(width 0)
				(type default)
			)
			(fill no)
			(layer "F.Fab")
		)
		(pad "1" smd custom
			(at 0 -0.4445 270)
			(size 0.1397 0.1397)
			(layers "F.Cu" "F.Mask" "F.Paste")
			(net "P5VA_ROVP")
			(options
				(clearance outline)
				(anchor circle)
			)
			(primitives
				(gr_poly
					(pts
						(arc
							(start -0.1778 -0.2794)
							(mid -0.249642 -0.249642)
							(end -0.2794 -0.1778)
						)
						(arc
							(start -0.2794 0.1778)
							(mid -0.249642 0.249642)
							(end -0.1778 0.2794)
						)
						(arc
							(start 0.1778 0.2794)
							(mid 0.249642 0.249642)
							(end 0.2794 0.1778)
						)
						(arc
							(start 0.2794 -0.1778)
							(mid 0.249642 -0.249642)
							(end 0.1778 -0.2794)
						)
					)
					(width 0)
					(fill yes)
				)
			)
		)
		(pad "2" smd custom
			(at 0 0.4445 270)
			(size 0.1397 0.1397)
			(layers "F.Cu" "F.Mask" "F.Paste")
			(net "P5VA_AGND")
			(options
				(clearance outline)
				(anchor circle)
			)
			(primitives
				(gr_poly
					(pts
						(arc
							(start -0.1778 -0.2794)
							(mid -0.249642 -0.249642)
							(end -0.2794 -0.1778)
						)
						(arc
							(start -0.2794 0.1778)
							(mid -0.249642 0.249642)
							(end -0.1778 0.2794)
						)
						(arc
							(start 0.1778 0.2794)
							(mid 0.249642 0.249642)
							(end 0.2794 0.1778)
						)
						(arc
							(start 0.2794 -0.1778)
							(mid 0.249642 -0.249642)
							(end 0.1778 -0.2794)
						)
					)
					(width 0)
					(fill yes)
				)
			)
		)
	)
	(footprint ""
		(layer "F.Cu")
		(at 55.371746 -389.1407 180)
		(property "Reference" "C205"
			(at 0 0 180)
			(layer "F.SilkS")
			(hide yes)
			(effects
				(font
					(size 1.27 1.27)
				)
			)
		)
		(property "Value" "SC1U16V3KX-5GP"
			(at 0 -2.8194 180)
			(unlocked yes)
			(layer "F.Fab")
			(hide yes)
			(effects
				(font
					(size 1.016 1.016)
					(thickness 0.1524)
				)
			)
		)
		(property "Device Type" "C603H36"
			(at 0 -4.3434 180)
			(unlocked yes)
			(layer "F.Fab")
			(hide yes)
			(effects
				(font
					(size 1.016 1.016)
					(thickness 0.1524)
				)
			)
		)
		(duplicate_pad_numbers_are_jumpers no)
		(fp_line
			(start 0.508 0)
			(end -0.508 0)
			(stroke
				(width 0.2032)
				(type default)
			)
			(layer "F.SilkS")
		)
		(fp_rect
			(start -0.5842 1.3335)
			(end 0.5842 -1.3335)
			(stroke
				(width 0)
				(type default)
			)
			(fill no)
			(layer "F.CrtYd")
		)
		(fp_rect
			(start -0.5842 1.3335)
			(end 0.5842 -1.3335)
			(stroke
				(width 0)
				(type default)
			)
			(fill no)
			(layer "F.Fab")
		)
		(pad "1" smd custom
			(at 0 -0.762 180)
			(size 0.2159 0.2159)
			(layers "F.Cu" "F.Mask" "F.Paste")
			(net "P5V_HDD6")
			(options
				(clearance outline)
				(anchor circle)
			)
			(primitives
				(gr_poly
					(pts
						(arc
							(start -0.3302 -0.4318)
							(mid -0.402042 -0.402042)
							(end -0.4318 -0.3302)
						)
						(arc
							(start -0.4318 0.3302)
							(mid -0.402042 0.402042)
							(end -0.3302 0.4318)
						)
						(arc
							(start 0.3302 0.4318)
							(mid 0.402042 0.402042)
							(end 0.4318 0.3302)
						)
						(arc
							(start 0.4318 -0.3302)
							(mid 0.402042 -0.402042)
							(end 0.3302 -0.4318)
						)
					)
					(width 0)
					(fill yes)
				)
			)
		)
		(pad "2" smd custom
			(at 0 0.762 180)
			(size 0.2159 0.2159)
			(layers "F.Cu" "F.Mask" "F.Paste")
			(net "GND")
			(options
				(clearance outline)
				(anchor circle)
			)
			(primitives
				(gr_poly
					(pts
						(arc
							(start -0.3302 -0.4318)
							(mid -0.402042 -0.402042)
							(end -0.4318 -0.3302)
						)
						(arc
							(start -0.4318 0.3302)
							(mid -0.402042 0.402042)
							(end -0.3302 0.4318)
						)
						(arc
							(start 0.3302 0.4318)
							(mid 0.402042 0.402042)
							(end 0.4318 0.3302)
						)
						(arc
							(start 0.4318 -0.3302)
							(mid 0.402042 -0.402042)
							(end 0.3302 -0.4318)
						)
					)
					(width 0)
					(fill yes)
				)
			)
		)
	)
	(footprint ""
		(layer "F.Cu")
		(at 245.9228 -421.767 -90)
		(property "Reference" "C355"
			(at 0 0 270)
			(layer "F.SilkS")
			(hide yes)
			(effects
				(font
					(size 1.27 1.27)
				)
			)
		)
		(property "Value" "SC220P50V3JN-GP"
			(at 0 -2.8194 270)
			(unlocked yes)
			(layer "F.Fab")
			(hide yes)
			(effects
				(font
					(size 1.016 1.016)
					(thickness 0.1524)
				)
			)
		)
		(property "Device Type" "C603H36"
			(at 0 -4.3434 270)
			(unlocked yes)
			(layer "F.Fab")
			(hide yes)
			(effects
				(font
					(size 1.016 1.016)
					(thickness 0.1524)
				)
			)
		)
		(duplicate_pad_numbers_are_jumpers no)
		(fp_line
			(start 0.508 0)
			(end -0.508 0)
			(stroke
				(width 0.2032)
				(type default)
			)
			(layer "F.SilkS")
		)
		(fp_rect
			(start -0.5842 1.3335)
			(end 0.5842 -1.3335)
			(stroke
				(width 0)
				(type default)
			)
			(fill no)
			(layer "F.CrtYd")
		)
		(fp_rect
			(start -0.5842 1.3335)
			(end 0.5842 -1.3335)
			(stroke
				(width 0)
				(type default)
			)
			(fill no)
			(layer "F.Fab")
		)
		(pad "1" smd custom
			(at 0 -0.762 270)
			(size 0.2159 0.2159)
			(layers "F.Cu" "F.Mask" "F.Paste")
			(net "I2C_C_SDA")
			(options
				(clearance outline)
				(anchor circle)
			)
			(primitives
				(gr_poly
					(pts
						(arc
							(start -0.3302 -0.4318)
							(mid -0.402042 -0.402042)
							(end -0.4318 -0.3302)
						)
						(arc
							(start -0.4318 0.3302)
							(mid -0.402042 0.402042)
							(end -0.3302 0.4318)
						)
						(arc
							(start 0.3302 0.4318)
							(mid 0.402042 0.402042)
							(end 0.4318 0.3302)
						)
						(arc
							(start 0.4318 -0.3302)
							(mid 0.402042 -0.402042)
							(end 0.3302 -0.4318)
						)
					)
					(width 0)
					(fill yes)
				)
			)
		)
		(pad "2" smd custom
			(at 0 0.762 270)
			(size 0.2159 0.2159)
			(layers "F.Cu" "F.Mask" "F.Paste")
			(net "GND")
			(options
				(clearance outline)
				(anchor circle)
			)
			(primitives
				(gr_poly
					(pts
						(arc
							(start -0.3302 -0.4318)
							(mid -0.402042 -0.402042)
							(end -0.4318 -0.3302)
						)
						(arc
							(start -0.4318 0.3302)
							(mid -0.402042 0.402042)
							(end -0.3302 0.4318)
						)
						(arc
							(start 0.3302 0.4318)
							(mid 0.402042 0.402042)
							(end 0.4318 0.3302)
						)
						(arc
							(start 0.4318 -0.3302)
							(mid 0.402042 -0.402042)
							(end 0.3302 -0.4318)
						)
					)
					(width 0)
					(fill yes)
				)
			)
		)
	)
)
